# T6G (Grand Teton) — schematic netlist excerpt (pin names and nets, part order shuffled) for the footprints in the layout excerpt that follows; sources: Cadence DE-HDL packaged netlist, KiCad conversion of 04192023_DAF0TMB3IC0_F0TG_MB_C_brd_V02_OCP.brd

PC297_4  Q_CAP  22UF 16V 20% X6S  pkg C0805  page 212 : A = SW_P12V_AUX_PVDDCR_CPU0_P1_FLT ; B = GND
C278  Q_CAP  22UF 4V 20% X6S  pkg C0402  page 69 : A = PVDDCR_CPU0_P0 ; B = GND
C207  Q_CAP  0.001UF 50V 10% EMPTY  pkg C0402  page 27 : A = JTAG_CPU0_TDO ; B = GND

(kicad_pcb
	(version 20260206)
	(generator "pcbnew")
	(generator_version "10.0")
	(general
		(thickness 1.6)
		(legacy_teardrops no)
	)
	(paper "A4")
	(title_block
		(title "04192023_DAF0TMB3IC0_F0TG_MB_C_brd_V02_OCP.brd")
		(comment 1 "Grand Teton / footprints 5374-5376 of 8354")
	)
	(layers
		(0 "F.Cu" signal "TOP")
		(4 "In1.Cu" signal "GND")
		(6 "In2.Cu" signal "IN1")
		(8 "In3.Cu" signal "GND1")
		(10 "In4.Cu" signal "IN2")
		(12 "In5.Cu" signal "GND2")
		(14 "In6.Cu" signal "IN3")
		(16 "In7.Cu" signal "GND3")
		(18 "In8.Cu" signal "VCC")
		(20 "In9.Cu" signal "VCC1")
		(22 "In10.Cu" signal "GND4")
		(24 "In11.Cu" signal "IN4")
		(26 "In12.Cu" signal "GND5")
		(28 "In13.Cu" signal "IN5")
		(30 "In14.Cu" signal "GND6")
		(32 "In15.Cu" signal "IN6")
		(34 "In16.Cu" signal "GND7")
		(2 "B.Cu" signal "BOTTOM")
		(9 "F.Adhes" user "F.Adhesive")
		(11 "B.Adhes" user "B.Adhesive")
		(13 "F.Paste" user "Package Geometry/Pastemask Top")
		(15 "B.Paste" user "Package Geometry/Pastemask Bottom")
		(5 "F.SilkS" user "Ref Des/Silkscreen Top")
		(7 "B.SilkS" user "Ref Des/Silkscreen Bottom")
		(1 "F.Mask" user "Board Geometry/Soldermask Top")
		(3 "B.Mask" user "Board Geometry/Soldermask Bottom")
		(17 "Dwgs.User" user "User.Drawings")
		(19 "Cmts.User" user "User.Comments")
		(21 "Eco1.User" user "User.Eco1")
		(23 "Eco2.User" user "User.Eco2")
		(25 "Edge.Cuts" user "Board Geometry/Outline")
		(27 "Margin" user)
		(31 "F.CrtYd" user "Package Geometry/Place Bound Top")
		(29 "B.CrtYd" user "Package Geometry/Place Bound Bottom")
		(35 "F.Fab" user "Ref Des/Assembly Top")
		(33 "B.Fab" user "Ref Des/Assembly Bottom")
	)
	(footprint ""
		(layer "B.Cu")
		(at 104.320848 -178.110134 -90)
		(property "Reference" "PC297_4"
			(at 0 0 90)
			(layer "B.SilkS")
			(hide yes)
			(effects
				(font
					(size 1.27 1.27)
				)
				(justify mirror)
			)
		)
		(property "Value" ""
			(at 0 0 90)
			(layer "B.Fab")
			(effects
				(font
					(size 1.27 1.27)
				)
				(justify mirror)
			)
		)
		(duplicate_pad_numbers_are_jumpers no)
		(fp_line
			(start -1.524 0.762)
			(end 1.524 0.762)
			(stroke
				(width 0.1524)
				(type default)
			)
			(layer "B.SilkS")
		)
		(fp_line
			(start 1.524 0.762)
			(end 1.524 -0.762)
			(stroke
				(width 0.1524)
				(type default)
			)
			(layer "B.SilkS")
		)
		(fp_line
			(start -1.524 -0.762)
			(end -1.524 0.762)
			(stroke
				(width 0.1524)
				(type default)
			)
			(layer "B.SilkS")
		)
		(fp_line
			(start 1.524 -0.762)
			(end -1.524 -0.762)
			(stroke
				(width 0.1524)
				(type default)
			)
			(layer "B.SilkS")
		)
		(fp_line
			(start -1.1049 0.724916)
			(end -1.1049 -0.724916)
			(stroke
				(width 0.1)
				(type default)
			)
			(layer "B.Fab")
		)
		(fp_line
			(start 1.1049 0.724916)
			(end -1.1049 0.724916)
			(stroke
				(width 0.1)
				(type default)
			)
			(layer "B.Fab")
		)
		(fp_line
			(start -1.1049 -0.724916)
			(end 1.1049 -0.724916)
			(stroke
				(width 0.1)
				(type default)
			)
			(layer "B.Fab")
		)
		(fp_line
			(start 1.1049 -0.724916)
			(end 1.1049 0.724916)
			(stroke
				(width 0.1)
				(type default)
			)
			(layer "B.Fab")
		)
		(pad "1" smd rect
			(at 0.889 0 270)
			(size 1.016 1.27)
			(layers "B.Cu" "B.Mask" "B.Paste")
			(net "SW_P12V_AUX_PVDDCR_CPU0_P1_FLT")
		)
		(pad "2" smd rect
			(at -0.889 0 270)
			(size 1.016 1.27)
			(layers "B.Cu" "B.Mask" "B.Paste")
			(net "GND")
		)
	)
	(footprint ""
		(layer "B.Cu")
		(at 375.202958 -205.101952 90)
		(property "Reference" "C207"
			(at 0 0 90)
			(layer "B.SilkS")
			(hide yes)
			(effects
				(font
					(size 1.27 1.27)
				)
				(justify mirror)
			)
		)
		(property "Value" ""
			(at 0 0 90)
			(layer "B.Fab")
			(effects
				(font
					(size 1.27 1.27)
				)
				(justify mirror)
			)
		)
		(duplicate_pad_numbers_are_jumpers no)
		(fp_line
			(start 0.7874 -0.4064)
			(end -0.7874 -0.4064)
			(stroke
				(width 0.1524)
				(type default)
			)
			(layer "B.SilkS")
		)
		(fp_line
			(start -0.7874 -0.4064)
			(end -0.7874 0.4064)
			(stroke
				(width 0.1524)
				(type default)
			)
			(layer "B.SilkS")
		)
		(fp_line
			(start 0.7874 0.4064)
			(end 0.7874 -0.4064)
			(stroke
				(width 0.1524)
				(type default)
			)
			(layer "B.SilkS")
		)
		(fp_line
			(start -0.7874 0.4064)
			(end 0.7874 0.4064)
			(stroke
				(width 0.1524)
				(type default)
			)
			(layer "B.SilkS")
		)
		(fp_line
			(start 0.67945 -0.305054)
			(end 0.12065 -0.305054)
			(stroke
				(width 0.1)
				(type default)
			)
			(layer "B.Fab")
		)
		(fp_line
			(start 0.12065 -0.305054)
			(end 0.12065 -0.2794)
			(stroke
				(width 0.1)
				(type default)
			)
			(layer "B.Fab")
		)
		(fp_line
			(start -0.12065 -0.3048)
			(end -0.67945 -0.3048)
			(stroke
				(width 0.1)
				(type default)
			)
			(layer "B.Fab")
		)
		(fp_line
			(start -0.67945 -0.3048)
			(end -0.67945 0.3048)
			(stroke
				(width 0.1)
				(type default)
			)
			(layer "B.Fab")
		)
		(fp_line
			(start 0.12065 -0.2794)
			(end -0.12065 -0.2794)
			(stroke
				(width 0.1)
				(type default)
			)
			(layer "B.Fab")
		)
		(fp_line
			(start -0.12065 -0.2794)
			(end -0.12065 -0.3048)
			(stroke
				(width 0.1)
				(type default)
			)
			(layer "B.Fab")
		)
		(fp_line
			(start 0.12065 0.2794)
			(end 0.12065 0.3048)
			(stroke
				(width 0.1)
				(type default)
			)
			(layer "B.Fab")
		)
		(fp_line
			(start -0.120396 0.2794)
			(end 0.12065 0.2794)
			(stroke
				(width 0.1)
				(type default)
			)
			(layer "B.Fab")
		)
		(fp_line
			(start 0.67945 0.3048)
			(end 0.67945 -0.305054)
			(stroke
				(width 0.1)
				(type default)
			)
			(layer "B.Fab")
		)
		(fp_line
			(start 0.12065 0.3048)
			(end 0.67945 0.3048)
			(stroke
				(width 0.1)
				(type default)
			)
			(layer "B.Fab")
		)
		(fp_line
			(start -0.120396 0.3048)
			(end -0.120396 0.2794)
			(stroke
				(width 0.1)
				(type default)
			)
			(layer "B.Fab")
		)
		(fp_line
			(start -0.67945 0.3048)
			(end -0.120396 0.3048)
			(stroke
				(width 0.1)
				(type default)
			)
			(layer "B.Fab")
		)
		(pad "1" smd circle
			(at 0.40005 0 270)
			(size 0 0)
			(layers "B.Cu" "B.Mask" "B.Paste")
			(net "JTAG_CPU0_TDO")
		)
		(pad "2" smd circle
			(at -0.40005 0 270)
			(size 0 0)
			(layers "B.Cu" "B.Mask" "B.Paste")
			(net "GND")
		)
	)
	(footprint ""
		(layer "B.Cu")
		(at 352.723958 -249.36831 180)
		(property "Reference" "C278"
			(at 0 0 0)
			(layer "B.SilkS")
			(hide yes)
			(effects
				(font
					(size 1.27 1.27)
				)
				(justify mirror)
			)
		)
		(property "Value" ""
			(at 0 0 0)
			(layer "B.Fab")
			(effects
				(font
					(size 1.27 1.27)
				)
				(justify mirror)
			)
		)
		(duplicate_pad_numbers_are_jumpers no)
		(fp_line
			(start 0.7874 0.4064)
			(end 0.7874 -0.4064)
			(stroke
				(width 0.1524)
				(type default)
			)
			(layer "B.SilkS")
		)
		(fp_line
			(start 0.7874 -0.4064)
			(end -0.7874 -0.4064)
			(stroke
				(width 0.1524)
				(type default)
			)
			(layer "B.SilkS")
		)
		(fp_line
			(start -0.7874 0.4064)
			(end 0.7874 0.4064)
			(stroke
				(width 0.1524)
				(type default)
			)
			(layer "B.SilkS")
		)
		(fp_line
			(start -0.7874 -0.4064)
			(end -0.7874 0.4064)
			(stroke
				(width 0.1524)
				(type default)
			)
			(layer "B.SilkS")
		)
		(fp_line
			(start 0.67945 0.3048)
			(end 0.67945 -0.305054)
			(stroke
				(width 0.1)
				(type default)
			)
			(layer "B.Fab")
		)
		(fp_line
			(start 0.67945 -0.305054)
			(end 0.12065 -0.305054)
			(stroke
				(width 0.1)
				(type default)
			)
			(layer "B.Fab")
		)
		(fp_line
			(start 0.12065 0.3048)
			(end 0.67945 0.3048)
			(stroke
				(width 0.1)
				(type default)
			)
			(layer "B.Fab")
		)
		(fp_line
			(start 0.12065 0.2794)
			(end 0.12065 0.3048)
			(stroke
				(width 0.1)
				(type default)
			)
			(layer "B.Fab")
		)
		(fp_line
			(start 0.12065 -0.2794)
			(end -0.12065 -0.2794)
			(stroke
				(width 0.1)
				(type default)
			)
			(layer "B.Fab")
		)
		(fp_line
			(start 0.12065 -0.305054)
			(end 0.12065 -0.2794)
			(stroke
				(width 0.1)
				(type default)
			)
			(layer "B.Fab")
		)
		(fp_line
			(start -0.120396 0.3048)
			(end -0.120396 0.2794)
			(stroke
				(width 0.1)
				(type default)
			)
			(layer "B.Fab")
		)
		(fp_line
			(start -0.120396 0.2794)
			(end 0.12065 0.2794)
			(stroke
				(width 0.1)
				(type default)
			)
			(layer "B.Fab")
		)
		(fp_line
			(start -0.12065 -0.2794)
			(end -0.12065 -0.3048)
			(stroke
				(width 0.1)
				(type default)
			)
			(layer "B.Fab")
		)
		(fp_line
			(start -0.12065 -0.3048)
			(end -0.67945 -0.3048)
			(stroke
				(width 0.1)
				(type default)
			)
			(layer "B.Fab")
		)
		(fp_line
			(start -0.67945 0.3048)
			(end -0.120396 0.3048)
			(stroke
				(width 0.1)
				(type default)
			)
			(layer "B.Fab")
		)
		(fp_line
			(start -0.67945 -0.3048)
			(end -0.67945 0.3048)
			(stroke
				(width 0.1)
				(type default)
			)
			(layer "B.Fab")
		)
		(pad "1" smd circle
			(at 0.40005 0)
			(size 0 0)
			(layers "B.Cu" "B.Mask" "B.Paste")
			(net "PVDDCR_CPU0_P0")
		)
		(pad "2" smd circle
			(at -0.40005 0)
			(size 0 0)
			(layers "B.Cu" "B.Mask" "B.Paste")
			(net "GND")
		)
	)
)
